# S9S_MB_2U (Grand Teton) — schematic netlist excerpt (pin names and nets, part order shuffled) for the footprints in the layout excerpt that follows; sources: Cadence DE-HDL packaged netlist, KiCad conversion of 03242023_DA0F0TMBIJ0_F0T_Motherboard_J_brd_V01_OCP.brd

C79  Q_CAP  10UF 16V 10% X6S  pkg C0805  page 111 : A = P12V_S3_AUX_CPU1_NVDIMM ; B = GND
R2553  Q_RES  100 1% CHIP  pkg 0402LF  page 284 : A = SVID_DIO0_CPU1_R ; B = PVNN_TERM_CPU1
C462  Q_CAP  47UF 4V 20% X6S  pkg C0805  page 79 : A = PVCCFA_EHV_FIVRA_CPU1 ; B = GND

(kicad_pcb
	(version 20260206)
	(generator "pcbnew")
	(generator_version "10.0")
	(general
		(thickness 1.6)
		(legacy_teardrops no)
	)
	(paper "A4")
	(title_block
		(title "03242023_DA0F0TMBIJ0_F0T_Motherboard_J_brd_V01_OCP.brd")
		(comment 1 "Grand Teton / footprints 5577-5579 of 6105")
	)
	(layers
		(0 "F.Cu" signal "TOP")
		(4 "In1.Cu" signal "GND")
		(6 "In2.Cu" signal "IN1")
		(8 "In3.Cu" signal "GND1")
		(10 "In4.Cu" signal "IN2")
		(12 "In5.Cu" signal "GND2")
		(14 "In6.Cu" signal "IN3")
		(16 "In7.Cu" signal "GND3")
		(18 "In8.Cu" signal "VCC")
		(20 "In9.Cu" signal "VCC1")
		(22 "In10.Cu" signal "GND4")
		(24 "In11.Cu" signal "IN4")
		(26 "In12.Cu" signal "GND5")
		(28 "In13.Cu" signal "IN5")
		(30 "In14.Cu" signal "GND6")
		(32 "In15.Cu" signal "IN6")
		(34 "In16.Cu" signal "GND7")
		(2 "B.Cu" signal "BOTTOM")
		(9 "F.Adhes" user "F.Adhesive")
		(11 "B.Adhes" user "B.Adhesive")
		(13 "F.Paste" user "Package Geometry/Pastemask Top")
		(15 "B.Paste" user "Package Geometry/Pastemask Bottom")
		(5 "F.SilkS" user "Ref Des/Silkscreen Top")
		(7 "B.SilkS" user "Ref Des/Silkscreen Bottom")
		(1 "F.Mask" user "Board Geometry/Soldermask Top")
		(3 "B.Mask" user "Board Geometry/Soldermask Bottom")
		(17 "Dwgs.User" user "User.Drawings")
		(19 "Cmts.User" user "User.Comments")
		(21 "Eco1.User" user "User.Eco1")
		(23 "Eco2.User" user "User.Eco2")
		(25 "Edge.Cuts" user "Board Geometry/Outline")
		(27 "Margin" user)
		(31 "F.CrtYd" user "Package Geometry/Place Bound Top")
		(29 "B.CrtYd" user "Package Geometry/Place Bound Bottom")
		(35 "F.Fab" user "Ref Des/Assembly Top")
		(33 "B.Fab" user "Ref Des/Assembly Bottom")
	)
	(footprint ""
		(layer "B.Cu")
		(at 60.978288 -250.767596 90)
		(property "Reference" "C462"
			(at 0 0 90)
			(layer "B.SilkS")
			(hide yes)
			(effects
				(font
					(size 1.27 1.27)
				)
				(justify mirror)
			)
		)
		(property "Value" ""
			(at 0 0 90)
			(layer "B.Fab")
			(effects
				(font
					(size 1.27 1.27)
				)
				(justify mirror)
			)
		)
		(duplicate_pad_numbers_are_jumpers no)
		(fp_line
			(start 1.524 -0.762)
			(end -1.524 -0.762)
			(stroke
				(width 0.1524)
				(type default)
			)
			(layer "B.SilkS")
		)
		(fp_line
			(start -1.524 -0.762)
			(end -1.524 0.762)
			(stroke
				(width 0.1524)
				(type default)
			)
			(layer "B.SilkS")
		)
		(fp_line
			(start 1.524 0.762)
			(end 1.524 -0.762)
			(stroke
				(width 0.1524)
				(type default)
			)
			(layer "B.SilkS")
		)
		(fp_line
			(start -1.524 0.762)
			(end 1.524 0.762)
			(stroke
				(width 0.1524)
				(type default)
			)
			(layer "B.SilkS")
		)
		(fp_line
			(start 1.1049 -0.724916)
			(end 1.1049 0.724916)
			(stroke
				(width 0.1)
				(type default)
			)
			(layer "B.Fab")
		)
		(fp_line
			(start -1.1049 -0.724916)
			(end 1.1049 -0.724916)
			(stroke
				(width 0.1)
				(type default)
			)
			(layer "B.Fab")
		)
		(fp_line
			(start 1.1049 0.724916)
			(end -1.1049 0.724916)
			(stroke
				(width 0.1)
				(type default)
			)
			(layer "B.Fab")
		)
		(fp_line
			(start -1.1049 0.724916)
			(end -1.1049 -0.724916)
			(stroke
				(width 0.1)
				(type default)
			)
			(layer "B.Fab")
		)
		(pad "1" smd rect
			(at 0.889 0 90)
			(size 1.016 1.27)
			(layers "B.Cu" "B.Mask" "B.Paste")
			(net "PVCCFA_EHV_FIVRA_CPU1")
		)
		(pad "2" smd rect
			(at -0.889 0 90)
			(size 1.016 1.27)
			(layers "B.Cu" "B.Mask" "B.Paste")
			(net "GND")
		)
	)
	(footprint ""
		(layer "B.Cu")
		(at 193.065146 -321.554856 -90)
		(property "Reference" "C79"
			(at 0 0 90)
			(layer "B.SilkS")
			(hide yes)
			(effects
				(font
					(size 1.27 1.27)
				)
				(justify mirror)
			)
		)
		(property "Value" ""
			(at 0 0 90)
			(layer "B.Fab")
			(effects
				(font
					(size 1.27 1.27)
				)
				(justify mirror)
			)
		)
		(duplicate_pad_numbers_are_jumpers no)
		(fp_line
			(start -1.524 0.762)
			(end 1.524 0.762)
			(stroke
				(width 0.1524)
				(type default)
			)
			(layer "B.SilkS")
		)
		(fp_line
			(start 1.524 0.762)
			(end 1.524 -0.762)
			(stroke
				(width 0.1524)
				(type default)
			)
			(layer "B.SilkS")
		)
		(fp_line
			(start -1.524 -0.762)
			(end -1.524 0.762)
			(stroke
				(width 0.1524)
				(type default)
			)
			(layer "B.SilkS")
		)
		(fp_line
			(start 1.524 -0.762)
			(end -1.524 -0.762)
			(stroke
				(width 0.1524)
				(type default)
			)
			(layer "B.SilkS")
		)
		(fp_line
			(start -1.1049 0.724916)
			(end -1.1049 -0.724916)
			(stroke
				(width 0.1)
				(type default)
			)
			(layer "B.Fab")
		)
		(fp_line
			(start 1.1049 0.724916)
			(end -1.1049 0.724916)
			(stroke
				(width 0.1)
				(type default)
			)
			(layer "B.Fab")
		)
		(fp_line
			(start -1.1049 -0.724916)
			(end 1.1049 -0.724916)
			(stroke
				(width 0.1)
				(type default)
			)
			(layer "B.Fab")
		)
		(fp_line
			(start 1.1049 -0.724916)
			(end 1.1049 0.724916)
			(stroke
				(width 0.1)
				(type default)
			)
			(layer "B.Fab")
		)
		(pad "1" smd rect
			(at 0.889 0 270)
			(size 1.016 1.27)
			(layers "B.Cu" "B.Mask" "B.Paste")
			(net "P12V_S3_AUX_CPU1_NVDIMM")
		)
		(pad "2" smd rect
			(at -0.889 0 270)
			(size 1.016 1.27)
			(layers "B.Cu" "B.Mask" "B.Paste")
			(net "GND")
		)
	)
	(footprint ""
		(layer "B.Cu")
		(at 100.306886 -356.63759)
		(property "Reference" "R2553"
			(at 0 0 0)
			(layer "B.SilkS")
			(hide yes)
			(effects
				(font
					(size 1.27 1.27)
				)
				(justify mirror)
			)
		)
		(property "Value" ""
			(at 0 0 0)
			(layer "B.Fab")
			(effects
				(font
					(size 1.27 1.27)
				)
				(justify mirror)
			)
		)
		(duplicate_pad_numbers_are_jumpers no)
		(fp_line
			(start -0.7874 -0.4064)
			(end -0.7874 0.4064)
			(stroke
				(width 0.1524)
				(type default)
			)
			(layer "B.SilkS")
		)
		(fp_line
			(start -0.7874 0.4064)
			(end 0.7874 0.4064)
			(stroke
				(width 0.1524)
				(type default)
			)
			(layer "B.SilkS")
		)
		(fp_line
			(start 0.7874 -0.4064)
			(end -0.7874 -0.4064)
			(stroke
				(width 0.1524)
				(type default)
			)
			(layer "B.SilkS")
		)
		(fp_line
			(start 0.7874 0.4064)
			(end 0.7874 -0.4064)
			(stroke
				(width 0.1524)
				(type default)
			)
			(layer "B.SilkS")
		)
		(fp_line
			(start -0.67945 -0.3048)
			(end -0.67945 0.3048)
			(stroke
				(width 0.1)
				(type default)
			)
			(layer "B.Fab")
		)
		(fp_line
			(start -0.67945 0.3048)
			(end -0.120396 0.3048)
			(stroke
				(width 0.1)
				(type default)
			)
			(layer "B.Fab")
		)
		(fp_line
			(start -0.12065 -0.3048)
			(end -0.67945 -0.3048)
			(stroke
				(width 0.1)
				(type default)
			)
			(layer "B.Fab")
		)
		(fp_line
			(start -0.12065 -0.2794)
			(end -0.12065 -0.3048)
			(stroke
				(width 0.1)
				(type default)
			)
			(layer "B.Fab")
		)
		(fp_line
			(start -0.120396 0.2794)
			(end 0.12065 0.2794)
			(stroke
				(width 0.1)
				(type default)
			)
			(layer "B.Fab")
		)
		(fp_line
			(start -0.120396 0.3048)
			(end -0.120396 0.2794)
			(stroke
				(width 0.1)
				(type default)
			)
			(layer "B.Fab")
		)
		(fp_line
			(start 0.12065 -0.305054)
			(end 0.12065 -0.2794)
			(stroke
				(width 0.1)
				(type default)
			)
			(layer "B.Fab")
		)
		(fp_line
			(start 0.12065 -0.2794)
			(end -0.12065 -0.2794)
			(stroke
				(width 0.1)
				(type default)
			)
			(layer "B.Fab")
		)
		(fp_line
			(start 0.12065 0.2794)
			(end 0.12065 0.3048)
			(stroke
				(width 0.1)
				(type default)
			)
			(layer "B.Fab")
		)
		(fp_line
			(start 0.12065 0.3048)
			(end 0.67945 0.3048)
			(stroke
				(width 0.1)
				(type default)
			)
			(layer "B.Fab")
		)
		(fp_line
			(start 0.67945 -0.305054)
			(end 0.12065 -0.305054)
			(stroke
				(width 0.1)
				(type default)
			)
			(layer "B.Fab")
		)
		(fp_line
			(start 0.67945 0.3048)
			(end 0.67945 -0.305054)
			(stroke
				(width 0.1)
				(type default)
			)
			(layer "B.Fab")
		)
		(pad "1" smd circle
			(at 0.40005 0 180)
			(size 0 0)
			(layers "B.Cu" "B.Mask" "B.Paste")
			(net "SVID_DIO0_CPU1_R")
		)
		(pad "2" smd circle
			(at -0.40005 0 180)
			(size 0 0)
			(layers "B.Cu" "B.Mask" "B.Paste")
			(net "PVNN_TERM_CPU1")
		)
	)
)
